FILE_TYPE = CONNECTIVITY;
{Allegro Design Entry HDL 16.6-p007 (v16-6-112F) 10/10/2012}
"PAGE_NUMBER" = 23;
0"NC";
1"M_A_DQ<63:0>";
2"M_A_ECC<7:0>";
3"M_A_CLK_DP<3:0>";
4"M_A_CLK_DN<3:0>";
5"M_A_ODT<3:0>";
6"M_A_MA<17:0>";
7"M_A_CS_N<7:0>";
8"M_A_CKE<3:0>";
9"M_A_BG<1:0>";
10"M_A_BA<1:0>";
11"M_A_DQS_DP<17:0>";
12"M_A_DQS_DN<17:0>";
13"M_A_DQ<54>";
14"M_A_DQ<40>";
15"M_A_DQS_DP<1>";
16"M_A_DQ<52>";
17"M_A_ODT<2>";
18"M_A_DQ<34>";
19"M_A_DQ<32>";
20"M_A_DQ<37>";
21"M_A_DQS_DP<17>";
22"M_A_DQS_DP<16>";
23"M_A_DQS_DP<15>";
24"M_A_DQS_DP<14>";
25"M_A_DQS_DP<13>";
26"M_A_DQS_DP<12>";
27"M_A_DQS_DP<11>";
28"M_A_DQS_DP<10>";
29"M_A_DQS_DP<9>";
30"M_A_DQS_DP<8>";
31"M_A_DQS_DP<7>";
32"M_A_DQS_DP<6>";
33"M_A_DQS_DP<5>";
34"M_A_DQS_DN<17>";
35"M_A_DQS_DN<16>";
36"M_A_DQS_DN<15>";
37"M_A_DQS_DN<14>";
38"M_A_DQS_DN<13>";
39"M_A_DQS_DN<12>";
40"M_A_DQS_DN<11>";
41"M_A_DQS_DN<10>";
42"M_A_DQS_DN<9>";
43"M_A_DQS_DN<8>";
44"M_A_DQS_DN<7>";
45"M_A_DQS_DN<6>";
46"M_A_DQS_DN<5>";
47"M_A_DQS_DN<4>";
48"M_A_DQS_DN<3>";
49"M_A_DQS_DN<2>";
50"M_A_DQS_DN<1>";
51"M_A_DQS_DN<0>";
52"M_A_DQS_DP<4>";
53"M_A_DQS_DP<3>";
54"M_A_DQS_DP<2>";
55"M_A_DQS_DP<0>";
56"M_A_MA<17>";
57"M_A_MA<16>";
58"M_A_MA<15>";
59"M_A_MA<14>";
60"M_A_MA<13>";
61"M_A_MA<12>";
62"M_A_MA<11>";
63"M_A_MA<10>";
64"M_A_MA<9>";
65"M_A_MA<8>";
66"M_A_MA<7>";
67"M_A_MA<6>";
68"M_A_MA<5>";
69"M_A_MA<4>";
70"M_A_MA<3>";
71"M_A_MA<2>";
72"M_A_ACT_N";
73"M_A_ALERT_N";
74"M_A_PAR";
75"M_A_BA<1>";
76"M_A_BA<0>";
77"M_A_BG<1>";
78"M_A_BG<0>";
79"M_A_CKE<3>";
80"M_A_CKE<2>";
81"M_A_CKE<1>";
82"M_A_CKE<0>";
83"M_A_CS_N<7>";
84"M_A_CS_N<6>";
85"M_A_CS_N<5>";
86"M_A_CS_N<4>";
87"M_A_CS_N<3>";
88"M_A_CS_N<2>";
89"M_A_CS_N<1>";
90"M_A_CS_N<0>";
91"M_A_MA<1>";
92"M_A_MA<0>";
93"M_A_ODT<3>";
94"M_A_ODT<1>";
95"M_A_ODT<0>";
96"M_A_DQ<63>";
97"M_A_DQ<62>";
98"M_A_DQ<61>";
99"M_A_DQ<60>";
100"M_A_DQ<59>";
101"M_A_DQ<58>";
102"M_A_DQ<57>";
103"M_A_DQ<56>";
104"M_A_DQ<55>";
105"M_A_DQ<53>";
106"M_A_DQ<51>";
107"M_A_DQ<50>";
108"M_A_DQ<49>";
109"M_A_DQ<48>";
110"M_A_DQ<47>";
111"M_A_DQ<46>";
112"M_A_DQ<45>";
113"M_A_DQ<44>";
114"M_A_DQ<43>";
115"M_A_DQ<42>";
116"M_A_DQ<41>";
117"M_A_DQ<39>";
118"M_A_DQ<38>";
119"M_A_DQ<36>";
120"M_A_DQ<35>";
121"M_A_DQ<33>";
122"M_A_DQ<31>";
123"M_A_DQ<30>";
124"M_A_DQ<29>";
125"M_A_DQ<28>";
126"M_A_DQ<27>";
127"M_A_DQ<26>";
128"M_A_DQ<25>";
129"M_A_DQ<24>";
130"M_A_DQ<23>";
131"M_A_DQ<22>";
132"M_A_DQ<21>";
133"M_A_DQ<20>";
134"M_A_DQ<19>";
135"M_A_DQ<18>";
136"M_A_DQ<17>";
137"M_A_DQ<16>";
138"M_A_DQ<15>";
139"M_A_DQ<14>";
140"M_A_DQ<13>";
141"M_A_DQ<12>";
142"M_A_DQ<11>";
143"M_A_DQ<10>";
144"M_A_CLK_DN<3>";
145"M_A_CLK_DN<2>";
146"M_A_CLK_DN<1>";
147"M_A_CLK_DN<0>";
148"M_A_CLK_DP<3>";
149"M_A_CLK_DP<2>";
150"M_A_CLK_DP<1>";
151"M_A_CLK_DP<0>";
152"M_A_DQ<9>";
153"M_A_DQ<8>";
154"M_A_DQ<7>";
155"M_A_DQ<6>";
156"M_A_DQ<5>";
157"M_A_DQ<3>";
158"M_A_DQ<2>";
159"M_A_DQ<1>";
160"M_A_DQ<0>";
161"M_A_ECC<7>";
162"M_A_ECC<6>";
163"M_A_ECC<5>";
164"M_A_ECC<4>";
165"M_A_ECC<3>";
166"M_A_ECC<2>";
167"M_A_ECC<1>";
168"M_A_ECC<0>";
169"M_A_C<2>";
170"M_A_DQ<4>";
%"TAP"
"6","(-5600,850)","0","mstr_standard","I10";
;
CDS_LIB"mstr_standard"
BODY_TYPE"PLUMBING"
HDL_TAP"TRUE";
"B \NAC \NWC"3;
"S \NAC"
BN"0"151;
%"TAP"
"6","(-2875,1600)","2","mstr_standard","I100";
;
CDS_LIB"mstr_standard"
BODY_TYPE"PLUMBING"
HDL_TAP"TRUE";
"B \NAC \NWC"5;
"S \NAC"
BN"3"93;
%"TAP"
"6","(-2875,1700)","2","mstr_standard","I101";
;
CDS_LIB"mstr_standard"
BODY_TYPE"PLUMBING"
HDL_TAP"TRUE";
"B \NAC \NWC"8;
"S \NAC"
BN"0"82;
%"TAP"
"6","(-2875,1550)","2","mstr_standard","I102";
;
CDS_LIB"mstr_standard"
BODY_TYPE"PLUMBING"
HDL_TAP"TRUE";
"B \NAC \NWC"5;
"S \NAC"
BN"2"17;
%"TAP"
"6","(-2875,1500)","2","mstr_standard","I103";
;
CDS_LIB"mstr_standard"
BODY_TYPE"PLUMBING"
HDL_TAP"TRUE";
"B \NAC \NWC"5;
"S \NAC"
BN"1"94;
%"TAP"
"6","(-2875,1850)","2","mstr_standard","I104";
;
CDS_LIB"mstr_standard"
BODY_TYPE"PLUMBING"
HDL_TAP"TRUE";
"B \NAC \NWC"8;
"S \NAC"
BN"3"79;
%"TAP"
"6","(-2875,1950)","2","mstr_standard","I105";
;
CDS_LIB"mstr_standard"
BODY_TYPE"PLUMBING"
HDL_TAP"TRUE";
"B \NAC \NWC"6;
"S \NAC"
BN"0"92;
%"TAP"
"6","(-2875,1800)","2","mstr_standard","I106";
;
CDS_LIB"mstr_standard"
BODY_TYPE"PLUMBING"
HDL_TAP"TRUE";
"B \NAC \NWC"8;
"S \NAC"
BN"2"80;
%"TAP"
"6","(-2875,1750)","2","mstr_standard","I107";
;
CDS_LIB"mstr_standard"
BODY_TYPE"PLUMBING"
HDL_TAP"TRUE";
"B \NAC \NWC"8;
"S \NAC"
BN"1"81;
%"TAP"
"6","(-2875,2000)","2","mstr_standard","I108";
;
CDS_LIB"mstr_standard"
BODY_TYPE"PLUMBING"
HDL_TAP"TRUE";
"B \NAC \NWC"6;
"S \NAC"
BN"1"91;
%"TAP"
"6","(-2875,2050)","2","mstr_standard","I109";
;
CDS_LIB"mstr_standard"
BODY_TYPE"PLUMBING"
HDL_TAP"TRUE";
"B \NAC \NWC"6;
"S \NAC"
BN"2"71;
%"TAP"
"6","(-5600,950)","0","mstr_standard","I11";
;
CDS_LIB"mstr_standard"
BODY_TYPE"PLUMBING"
HDL_TAP"TRUE";
"B \NAC \NWC"3;
"S \NAC"
BN"2"149;
%"TAP"
"6","(-2875,2100)","2","mstr_standard","I110";
;
CDS_LIB"mstr_standard"
BODY_TYPE"PLUMBING"
HDL_TAP"TRUE";
"B \NAC \NWC"6;
"S \NAC"
BN"3"70;
%"TAP"
"6","(-2875,2250)","2","mstr_standard","I111";
;
CDS_LIB"mstr_standard"
BODY_TYPE"PLUMBING"
HDL_TAP"TRUE";
"B \NAC \NWC"6;
"S \NAC"
BN"6"67;
%"TAP"
"6","(-2875,2200)","2","mstr_standard","I112";
;
CDS_LIB"mstr_standard"
BODY_TYPE"PLUMBING"
HDL_TAP"TRUE";
"B \NAC \NWC"6;
"S \NAC"
BN"5"68;
%"TAP"
"6","(-2875,2150)","2","mstr_standard","I113";
;
CDS_LIB"mstr_standard"
BODY_TYPE"PLUMBING"
HDL_TAP"TRUE";
"B \NAC \NWC"6;
"S \NAC"
BN"4"69;
%"TAP"
"6","(-2875,2400)","2","mstr_standard","I114";
;
CDS_LIB"mstr_standard"
BODY_TYPE"PLUMBING"
HDL_TAP"TRUE";
"B \NAC \NWC"6;
"S \NAC"
BN"9"64;
%"TAP"
"6","(-2875,2450)","2","mstr_standard","I115";
;
CDS_LIB"mstr_standard"
BODY_TYPE"PLUMBING"
HDL_TAP"TRUE";
"B \NAC \NWC"6;
"S \NAC"
BN"10"63;
%"TAP"
"6","(-2875,2500)","2","mstr_standard","I116";
;
CDS_LIB"mstr_standard"
BODY_TYPE"PLUMBING"
HDL_TAP"TRUE";
"B \NAC \NWC"6;
"S \NAC"
BN"11"62;
%"TAP"
"6","(-2875,2350)","2","mstr_standard","I117";
;
CDS_LIB"mstr_standard"
BODY_TYPE"PLUMBING"
HDL_TAP"TRUE";
"B \NAC \NWC"6;
"S \NAC"
BN"8"65;
%"TAP"
"6","(-2875,2300)","2","mstr_standard","I118";
;
CDS_LIB"mstr_standard"
BODY_TYPE"PLUMBING"
HDL_TAP"TRUE";
"B \NAC \NWC"6;
"S \NAC"
BN"7"66;
%"TAP"
"6","(-2875,2650)","2","mstr_standard","I119";
;
CDS_LIB"mstr_standard"
BODY_TYPE"PLUMBING"
HDL_TAP"TRUE";
"B \NAC \NWC"6;
"S \NAC"
BN"14"59;
%"TAP"
"6","(-5600,1000)","0","mstr_standard","I12";
;
CDS_LIB"mstr_standard"
BODY_TYPE"PLUMBING"
HDL_TAP"TRUE";
"B \NAC \NWC"3;
"S \NAC"
BN"3"148;
%"TAP"
"6","(-2875,2700)","2","mstr_standard","I120";
;
CDS_LIB"mstr_standard"
BODY_TYPE"PLUMBING"
HDL_TAP"TRUE";
"B \NAC \NWC"6;
"S \NAC"
BN"15"58;
%"TAP"
"6","(-2875,2750)","2","mstr_standard","I121";
;
CDS_LIB"mstr_standard"
BODY_TYPE"PLUMBING"
HDL_TAP"TRUE";
"B \NAC \NWC"6;
"S \NAC"
BN"16"57;
%"TAP"
"6","(-2875,2600)","2","mstr_standard","I122";
;
CDS_LIB"mstr_standard"
BODY_TYPE"PLUMBING"
HDL_TAP"TRUE";
"B \NAC \NWC"6;
"S \NAC"
BN"13"60;
%"TAP"
"6","(-2875,2550)","2","mstr_standard","I123";
;
CDS_LIB"mstr_standard"
BODY_TYPE"PLUMBING"
HDL_TAP"TRUE";
"B \NAC \NWC"6;
"S \NAC"
BN"12"61;
%"TAP"
"6","(-2875,2900)","2","mstr_standard","I124";
;
CDS_LIB"mstr_standard"
BODY_TYPE"PLUMBING"
HDL_TAP"TRUE";
"B \NAC \NWC"12;
"S \NAC"
BN"0"51;
%"TAP"
"6","(-2875,3000)","2","mstr_standard","I125";
;
CDS_LIB"mstr_standard"
BODY_TYPE"PLUMBING"
HDL_TAP"TRUE";
"B \NAC \NWC"12;
"S \NAC"
BN"2"49;
%"TAP"
"6","(-2875,2950)","2","mstr_standard","I126";
;
CDS_LIB"mstr_standard"
BODY_TYPE"PLUMBING"
HDL_TAP"TRUE";
"B \NAC \NWC"12;
"S \NAC"
BN"1"50;
%"TAP"
"6","(-2875,2800)","2","mstr_standard","I127";
;
CDS_LIB"mstr_standard"
BODY_TYPE"PLUMBING"
HDL_TAP"TRUE";
"B \NAC \NWC"6;
"S \NAC"
BN"17"56;
%"TAP"
"6","(-2875,3200)","2","mstr_standard","I128";
;
CDS_LIB"mstr_standard"
BODY_TYPE"PLUMBING"
HDL_TAP"TRUE";
"B \NAC \NWC"12;
"S \NAC"
BN"6"45;
%"TAP"
"6","(-2875,3250)","2","mstr_standard","I129";
;
CDS_LIB"mstr_standard"
BODY_TYPE"PLUMBING"
HDL_TAP"TRUE";
"B \NAC \NWC"12;
"S \NAC"
BN"7"44;
%"TAP"
"6","(-5600,1100)","0","mstr_standard","I13";
;
CDS_LIB"mstr_standard"
BODY_TYPE"PLUMBING"
HDL_TAP"TRUE";
"B \NAC \NWC"2;
"S \NAC"
BN"0"168;
%"TAP"
"6","(-2875,3150)","2","mstr_standard","I130";
;
CDS_LIB"mstr_standard"
BODY_TYPE"PLUMBING"
HDL_TAP"TRUE";
"B \NAC \NWC"12;
"S \NAC"
BN"5"46;
%"TAP"
"6","(-2875,3100)","2","mstr_standard","I131";
;
CDS_LIB"mstr_standard"
BODY_TYPE"PLUMBING"
HDL_TAP"TRUE";
"B \NAC \NWC"12;
"S \NAC"
BN"4"47;
%"TAP"
"6","(-2875,3050)","2","mstr_standard","I132";
;
CDS_LIB"mstr_standard"
BODY_TYPE"PLUMBING"
HDL_TAP"TRUE";
"B \NAC \NWC"12;
"S \NAC"
BN"3"48;
%"TAP"
"6","(-2875,3500)","2","mstr_standard","I133";
;
CDS_LIB"mstr_standard"
BODY_TYPE"PLUMBING"
HDL_TAP"TRUE";
"B \NAC \NWC"12;
"S \NAC"
BN"12"39;
%"TAP"
"6","(-2875,3450)","2","mstr_standard","I134";
;
CDS_LIB"mstr_standard"
BODY_TYPE"PLUMBING"
HDL_TAP"TRUE";
"B \NAC \NWC"12;
"S \NAC"
BN"11"40;
%"TAP"
"6","(-2875,3400)","2","mstr_standard","I135";
;
CDS_LIB"mstr_standard"
BODY_TYPE"PLUMBING"
HDL_TAP"TRUE";
"B \NAC \NWC"12;
"S \NAC"
BN"10"41;
%"TAP"
"6","(-2875,3350)","2","mstr_standard","I136";
;
CDS_LIB"mstr_standard"
BODY_TYPE"PLUMBING"
HDL_TAP"TRUE";
"B \NAC \NWC"12;
"S \NAC"
BN"9"42;
%"TAP"
"6","(-2875,3300)","2","mstr_standard","I137";
;
CDS_LIB"mstr_standard"
BODY_TYPE"PLUMBING"
HDL_TAP"TRUE";
"B \NAC \NWC"12;
"S \NAC"
BN"8"43;
%"TAP"
"6","(-2875,3700)","2","mstr_standard","I138";
;
CDS_LIB"mstr_standard"
BODY_TYPE"PLUMBING"
HDL_TAP"TRUE";
"B \NAC \NWC"12;
"S \NAC"
BN"16"35;
%"TAP"
"6","(-2875,3750)","2","mstr_standard","I139";
;
CDS_LIB"mstr_standard"
BODY_TYPE"PLUMBING"
HDL_TAP"TRUE";
"B \NAC \NWC"12;
"S \NAC"
BN"17"34;
%"TAP"
"6","(-5600,1150)","0","mstr_standard","I14";
;
CDS_LIB"mstr_standard"
BODY_TYPE"PLUMBING"
HDL_TAP"TRUE";
"B \NAC \NWC"2;
"S \NAC"
BN"1"167;
%"TAP"
"6","(-2875,3650)","2","mstr_standard","I140";
;
CDS_LIB"mstr_standard"
BODY_TYPE"PLUMBING"
HDL_TAP"TRUE";
"B \NAC \NWC"12;
"S \NAC"
BN"15"36;
%"TAP"
"6","(-2875,3600)","2","mstr_standard","I141";
;
CDS_LIB"mstr_standard"
BODY_TYPE"PLUMBING"
HDL_TAP"TRUE";
"B \NAC \NWC"12;
"S \NAC"
BN"14"37;
%"TAP"
"6","(-2875,3550)","2","mstr_standard","I142";
;
CDS_LIB"mstr_standard"
BODY_TYPE"PLUMBING"
HDL_TAP"TRUE";
"B \NAC \NWC"12;
"S \NAC"
BN"13"38;
%"TAP"
"6","(-2875,3950)","2","mstr_standard","I143";
;
CDS_LIB"mstr_standard"
BODY_TYPE"PLUMBING"
HDL_TAP"TRUE";
"B \NAC \NWC"11;
"S \NAC"
BN"2"54;
%"TAP"
"6","(-2875,4000)","2","mstr_standard","I144";
;
CDS_LIB"mstr_standard"
BODY_TYPE"PLUMBING"
HDL_TAP"TRUE";
"B \NAC \NWC"11;
"S \NAC"
BN"3"53;
%"TAP"
"6","(-2875,3900)","2","mstr_standard","I145";
;
CDS_LIB"mstr_standard"
BODY_TYPE"PLUMBING"
HDL_TAP"TRUE";
"B \NAC \NWC"11;
"S \NAC"
BN"1"15;
%"TAP"
"6","(-2875,3850)","2","mstr_standard","I146";
;
CDS_LIB"mstr_standard"
BODY_TYPE"PLUMBING"
HDL_TAP"TRUE";
"B \NAC \NWC"11;
"S \NAC"
BN"0"55;
%"TAP"
"6","(-5600,1200)","0","mstr_standard","I15";
;
CDS_LIB"mstr_standard"
BODY_TYPE"PLUMBING"
HDL_TAP"TRUE";
"B \NAC \NWC"2;
"S \NAC"
BN"2"166;
%"TAP"
"6","(-2875,4050)","2","mstr_standard","I157";
;
CDS_LIB"mstr_standard"
BODY_TYPE"PLUMBING"
HDL_TAP"TRUE";
"B \NAC \NWC"11;
"S \NAC"
BN"4"52;
%"TAP"
"6","(-2875,4100)","2","mstr_standard","I158";
;
CDS_LIB"mstr_standard"
BODY_TYPE"PLUMBING"
HDL_TAP"TRUE";
"B \NAC \NWC"11;
"S \NAC"
BN"5"33;
%"TAP"
"6","(-2875,4150)","2","mstr_standard","I159";
;
CDS_LIB"mstr_standard"
BODY_TYPE"PLUMBING"
HDL_TAP"TRUE";
"B \NAC \NWC"11;
"S \NAC"
BN"6"32;
%"TAP"
"6","(-5600,1300)","0","mstr_standard","I16";
;
CDS_LIB"mstr_standard"
BODY_TYPE"PLUMBING"
HDL_TAP"TRUE";
"B \NAC \NWC"2;
"S \NAC"
BN"4"164;
%"TAP"
"6","(-2875,4300)","2","mstr_standard","I160";
;
CDS_LIB"mstr_standard"
BODY_TYPE"PLUMBING"
HDL_TAP"TRUE";
"B \NAC \NWC"11;
"S \NAC"
BN"9"29;
%"TAP"
"6","(-2875,4250)","2","mstr_standard","I161";
;
CDS_LIB"mstr_standard"
BODY_TYPE"PLUMBING"
HDL_TAP"TRUE";
"B \NAC \NWC"11;
"S \NAC"
BN"8"30;
%"TAP"
"6","(-2875,4200)","2","mstr_standard","I162";
;
CDS_LIB"mstr_standard"
BODY_TYPE"PLUMBING"
HDL_TAP"TRUE";
"B \NAC \NWC"11;
"S \NAC"
BN"7"31;
%"TAP"
"6","(-2875,4450)","2","mstr_standard","I163";
;
CDS_LIB"mstr_standard"
BODY_TYPE"PLUMBING"
HDL_TAP"TRUE";
"B \NAC \NWC"11;
"S \NAC"
BN"12"26;
%"TAP"
"6","(-2875,4500)","2","mstr_standard","I164";
;
CDS_LIB"mstr_standard"
BODY_TYPE"PLUMBING"
HDL_TAP"TRUE";
"B \NAC \NWC"11;
"S \NAC"
BN"13"25;
%"TAP"
"6","(-2875,4550)","2","mstr_standard","I165";
;
CDS_LIB"mstr_standard"
BODY_TYPE"PLUMBING"
HDL_TAP"TRUE";
"B \NAC \NWC"11;
"S \NAC"
BN"14"24;
%"TAP"
"6","(-2875,4400)","2","mstr_standard","I166";
;
CDS_LIB"mstr_standard"
BODY_TYPE"PLUMBING"
HDL_TAP"TRUE";
"B \NAC \NWC"11;
"S \NAC"
BN"11"27;
%"TAP"
"6","(-2875,4350)","2","mstr_standard","I167";
;
CDS_LIB"mstr_standard"
BODY_TYPE"PLUMBING"
HDL_TAP"TRUE";
"B \NAC \NWC"11;
"S \NAC"
BN"10"28;
%"TAP"
"6","(-2875,4700)","2","mstr_standard","I168";
;
CDS_LIB"mstr_standard"
BODY_TYPE"PLUMBING"
HDL_TAP"TRUE";
"B \NAC \NWC"11;
"S \NAC"
BN"17"21;
%"TAP"
"6","(-2875,4600)","2","mstr_standard","I169";
;
CDS_LIB"mstr_standard"
BODY_TYPE"PLUMBING"
HDL_TAP"TRUE";
"B \NAC \NWC"11;
"S \NAC"
BN"15"23;
%"TAP"
"6","(-5600,1250)","0","mstr_standard","I17";
;
CDS_LIB"mstr_standard"
BODY_TYPE"PLUMBING"
HDL_TAP"TRUE";
"B \NAC \NWC"2;
"S \NAC"
BN"3"165;
%"TAP"
"6","(-2875,4650)","2","mstr_standard","I170";
;
CDS_LIB"mstr_standard"
BODY_TYPE"PLUMBING"
HDL_TAP"TRUE";
"B \NAC \NWC"11;
"S \NAC"
BN"16"22;
%"SKX_EXT_B"
"3","(-4200,2600)","0","chpset_lib","I172";
;
CDS_SEC"3"
LOCATION"U5D1"
PART_NUMBER"TBD"
MATERIAL"IC"
PACK_TYPE"BGA1"
CDS_LIB"chpset_lib"
SEC_TYPE"BGA1"
SEC"3"
CDS_LOCATION"U5D1"
ROOM"CPU0";
"DDR0_PAR"
$PN"D53"74;
"DDR0_ODT<0>"
$PN"C50"95;
"DDR0_ODT<1>"
$PN"C48"94;
"DDR0_ODT<2>"
$PN"G50"17;
"DDR0_ODT<3>"
$PN"G48"93;
"DDR0_MA<0>"
$PN"F53"92;
"DDR0_MA<1>"
$PN"F57"91;
"DDR0_MA<2>"
$PN"D57"71;
"DDR0_MA<3>"
$PN"C58"70;
"DDR0_MA<4>"
$PN"G58"69;
"DDR0_MA<5>"
$PN"F59"68;
"DDR0_MA<6>"
$PN"D59"67;
"DDR0_MA<7>"
$PN"G60"66;
"DDR0_MA<8>"
$PN"C60"65;
"DDR0_MA<9>"
$PN"F61"64;
"DDR0_MA<10>"
$PN"J54"63;
"DDR0_MA<11>"
$PN"G62"62;
"DDR0_MA<12>"
$PN"J64"61;
"DDR0_MA<13>"
$PN"J48"60;
"DDR0_MA<14>"
$PN"F51"59;
"DDR0_MA<15>"
$PN"K49"58;
"DDR0_MA<16>"
$PN"D51"57;
"DDR0_MA<17>"
$PN"K47"56;
"DDR0_ECC<0>"
$PN"AC68"168;
"DDR0_ECC<1>"
$PN"AG68"167;
"DDR0_ECC<2>"
$PN"AD65"166;
"DDR0_ECC<3>"
$PN"AF65"165;
"DDR0_ECC<4>"
$PN"AD69"164;
"DDR0_ECC<5>"
$PN"AF69"163;
"DDR0_ECC<6>"
$PN"AC66"162;
"DDR0_ECC<7>"
$PN"AG66"161;
"DDR0_DQS_DP<0>"
$PN"AH85"55;
"DDR0_DQS_DP<1>"
$PN"P85"15;
"DDR0_DQS_DP<2>"
$PN"R80"54;
"DDR0_DQS_DP<3>"
$PN"P75"53;
"DDR0_DQS_DP<4>"
$PN"E40"52;
"DDR0_DQS_DP<5>"
$PN"N36"33;
"DDR0_DQS_DP<6>"
$PN"N30"32;
"DDR0_DQS_DP<7>"
$PN"R24"31;
"DDR0_DQS_DP<8>"
$PN"AF67"30;
"DDR0_DQS_DP<9>"
$PN"AM85"29;
"DDR0_DQS_DP<10>"
$PN"V85"28;
"DDR0_DQS_DP<11>"
$PN"T81"27;
"DDR0_DQS_DP<12>"
$PN"M75"26;
"DDR0_DQS_DP<13>"
$PN"C40"25;
"DDR0_DQS_DP<14>"
$PN"L36"24;
"DDR0_DQS_DP<15>"
$PN"L30"23;
"DDR0_DQS_DP<16>"
$PN"L24"22;
"DDR0_DQS_DP<17>"
$PN"AD67"21;
"DDR0_DQS_DN<0>"
$PN"AJ84"51;
"DDR0_DQS_DN<1>"
$PN"R84"50;
"DDR0_DQS_DN<2>"
$PN"P79"49;
"DDR0_DQS_DN<3>"
$PN"T75"48;
"DDR0_DQS_DN<4>"
$PN"G40"47;
"DDR0_DQS_DN<5>"
$PN"R36"46;
"DDR0_DQS_DN<6>"
$PN"R30"45;
"DDR0_DQS_DN<7>"
$PN"N24"44;
"DDR0_DQS_DN<8>"
$PN"AH67"43;
"DDR0_DQS_DN<9>"
$PN"AL84"42;
"DDR0_DQS_DN<10>"
$PN"U84"41;
"DDR0_DQS_DN<11>"
$PN"U82"40;
"DDR0_DQS_DN<12>"
$PN"K75"39;
"DDR0_DQS_DN<13>"
$PN"A40"38;
"DDR0_DQS_DN<14>"
$PN"J36"37;
"DDR0_DQS_DN<15>"
$PN"J30"36;
"DDR0_DQS_DN<16>"
$PN"J24"35;
"DDR0_DQS_DN<17>"
$PN"AB67"34;
"DDR0_DQ<0>"
$PN"AN86"160;
"DDR0_DQ<1>"
$PN"AN84"159;
"DDR0_DQ<2>"
$PN"AE86"158;
"DDR0_DQ<3>"
$PN"AE84"157;
"DDR0_DQ<4>"
$PN"AR86"170;
"DDR0_DQ<5>"
$PN"AR84"156;
"DDR0_DQ<6>"
$PN"AG86"155;
"DDR0_DQ<7>"
$PN"AG84"154;
"DDR0_DQ<8>"
$PN"W86"153;
"DDR0_DQ<9>"
$PN"W84"152;
"DDR0_DQ<10>"
$PN"L86"143;
"DDR0_DQ<11>"
$PN"L84"142;
"DDR0_DQ<12>"
$PN"AA86"141;
"DDR0_DQ<13>"
$PN"AA84"140;
"DDR0_DQ<14>"
$PN"N86"139;
"DDR0_DQ<15>"
$PN"N84"138;
"DDR0_DQ<16>"
$PN"V81"137;
"DDR0_DQ<17>"
$PN"T79"136;
"DDR0_DQ<18>"
$PN"N82"135;
"DDR0_DQ<19>"
$PN"M81"134;
"DDR0_DQ<20>"
$PN"W80"133;
"DDR0_DQ<21>"
$PN"V79"132;
"DDR0_DQ<22>"
$PN"R82"131;
"DDR0_DQ<23>"
$PN"N80"130;
"DDR0_DQ<24>"
$PN"L76"129;
"DDR0_DQ<25>"
$PN"R76"128;
"DDR0_DQ<26>"
$PN"M73"127;
"DDR0_DQ<27>"
$PN"P73"126;
"DDR0_DQ<28>"
$PN"M77"125;
"DDR0_DQ<29>"
$PN"P77"124;
"DDR0_DQ<30>"
$PN"L74"123;
"DDR0_DQ<31>"
$PN"R74"122;
"DDR0_DQ<32>"
$PN"C42"19;
"DDR0_DQ<33>"
$PN"B41"121;
"DDR0_DQ<34>"
$PN"C38"18;
"DDR0_DQ<35>"
$PN"E38"120;
"DDR0_DQ<36>"
$PN"E42"119;
"DDR0_DQ<37>"
$PN"F41"20;
"DDR0_DQ<38>"
$PN"B39"118;
"DDR0_DQ<39>"
$PN"F39"117;
"DDR0_DQ<40>"
$PN"K37"14;
"DDR0_DQ<41>"
$PN"P37"116;
"DDR0_DQ<42>"
$PN"L34"115;
"DDR0_DQ<43>"
$PN"N34"114;
"DDR0_DQ<44>"
$PN"L38"113;
"DDR0_DQ<45>"
$PN"N38"112;
"DDR0_DQ<46>"
$PN"K35"111;
"DDR0_DQ<47>"
$PN"P35"110;
"DDR0_DQ<48>"
$PN"K31"109;
"DDR0_DQ<49>"
$PN"P31"108;
"DDR0_DQ<50>"
$PN"L28"107;
"DDR0_DQ<51>"
$PN"N28"106;
"DDR0_DQ<52>"
$PN"L32"16;
"DDR0_DQ<53>"
$PN"N32"105;
"DDR0_DQ<54>"
$PN"K29"13;
"DDR0_DQ<55>"
$PN"P29"104;
"DDR0_DQ<56>"
$PN"K25"103;
"DDR0_DQ<57>"
$PN"P25"102;
"DDR0_DQ<58>"
$PN"P23"101;
"DDR0_DQ<59>"
$PN"T23"100;
"DDR0_DQ<60>"
$PN"L26"99;
"DDR0_DQ<61>"
$PN"N26"98;
"DDR0_DQ<62>"
$PN"H23"97;
"DDR0_DQ<63>"
$PN"K23"96;
"DDR0_CS_N<0>"
$PN"G52"90;
"DDR0_CS_N<1>"
$PN"F49"89;
"DDR0_CS_N<2>"
$PN"D47"88;
"DDR0_CS_N<3>"
$PN"F47"87;
"DDR0_CS_N<4>"
$PN"B51"86;
"DDR0_CS_N<5>"
$PN"D49"85;
"DDR0_CS_N<6>"
$PN"F45"84;
"DDR0_CS_N<7>"
$PN"K45"83;
"DDR0_CLK_DP<0>"
$PN"D55"151;
"DDR0_CLK_DP<1>"
$PN"B55"150;
"DDR0_CLK_DP<2>"
$PN"G56"149;
"DDR0_CLK_DP<3>"
$PN"B57"148;
"DDR0_CLK_DN<0>"
$PN"F55"147;
"DDR0_CLK_DN<1>"
$PN"C54"146;
"DDR0_CLK_DN<2>"
$PN"J56"145;
"DDR0_CLK_DN<3>"
$PN"C56"144;
"DDR0_CKE<0>"
$PN"C62"82;
"DDR0_CKE<1>"
$PN"C64"81;
"DDR0_CKE<2>"
$PN"B63"80;
"DDR0_CKE<3>"
$PN"D63"79;
"DDR0_CID<2>"
$PN"G46"169;
"DDR0_BG<0>"
$PN"D61"78;
"DDR0_BG<1>"
$PN"F63"77;
"DDR0_BA<0>"
$PN"C52"76;
"DDR0_BA<1>"
$PN"G54"75;
"DDR0_ALERT_N"
$PN"B61"73;
"DDR0_ACT_N"
$PN"J60"72;
%"TAP"
"6","(-5600,1350)","0","mstr_standard","I18";
;
CDS_LIB"mstr_standard"
BODY_TYPE"PLUMBING"
HDL_TAP"TRUE";
"B \NAC \NWC"2;
"S \NAC"
BN"5"163;
%"TAP"
"6","(-5600,1400)","0","mstr_standard","I19";
;
CDS_LIB"mstr_standard"
BODY_TYPE"PLUMBING"
HDL_TAP"TRUE";
"B \NAC \NWC"2;
"S \NAC"
BN"6"162;
%"TAP"
"6","(-5600,1450)","0","mstr_standard","I20";
;
CDS_LIB"mstr_standard"
BODY_TYPE"PLUMBING"
HDL_TAP"TRUE";
"B \NAC \NWC"2;
"S \NAC"
BN"7"161;
%"TAP"
"6","(-5600,1600)","0","mstr_standard","I21";
;
CDS_LIB"mstr_standard"
BODY_TYPE"PLUMBING"
HDL_TAP"TRUE";
"B \NAC \NWC"1;
"S \NAC"
BN"1"159;
%"TAP"
"6","(-5600,1550)","0","mstr_standard","I22";
;
CDS_LIB"mstr_standard"
BODY_TYPE"PLUMBING"
HDL_TAP"TRUE";
"B \NAC \NWC"1;
"S \NAC"
BN"0"160;
%"TAP"
"6","(-5600,1650)","0","mstr_standard","I23";
;
CDS_LIB"mstr_standard"
BODY_TYPE"PLUMBING"
HDL_TAP"TRUE";
"B \NAC \NWC"1;
"S \NAC"
BN"2"158;
%"TAP"
"6","(-5600,1700)","0","mstr_standard","I24";
;
CDS_LIB"mstr_standard"
BODY_TYPE"PLUMBING"
HDL_TAP"TRUE";
"B \NAC \NWC"1;
"S \NAC"
BN"3"157;
%"TAP"
"6","(-5600,1750)","0","mstr_standard","I25";
;
CDS_LIB"mstr_standard"
BODY_TYPE"PLUMBING"
HDL_TAP"TRUE";
"B \NAC \NWC"1;
"S \NAC"
BN"4"170;
%"TAP"
"6","(-5600,1800)","0","mstr_standard","I26";
;
CDS_LIB"mstr_standard"
BODY_TYPE"PLUMBING"
HDL_TAP"TRUE";
"B \NAC \NWC"1;
"S \NAC"
BN"5"156;
%"TAP"
"6","(-5600,1850)","0","mstr_standard","I27";
;
CDS_LIB"mstr_standard"
BODY_TYPE"PLUMBING"
HDL_TAP"TRUE";
"B \NAC \NWC"1;
"S \NAC"
BN"6"155;
%"TAP"
"6","(-5600,1950)","0","mstr_standard","I28";
;
CDS_LIB"mstr_standard"
BODY_TYPE"PLUMBING"
HDL_TAP"TRUE";
"B \NAC \NWC"1;
"S \NAC"
BN"8"153;
%"TAP"
"6","(-5600,1900)","0","mstr_standard","I29";
;
CDS_LIB"mstr_standard"
BODY_TYPE"PLUMBING"
HDL_TAP"TRUE";
"B \NAC \NWC"1;
"S \NAC"
BN"7"154;
%"TAP"
"6","(-5600,2000)","0","mstr_standard","I31";
;
CDS_LIB"mstr_standard"
BODY_TYPE"PLUMBING"
HDL_TAP"TRUE";
"B \NAC \NWC"1;
"S \NAC"
BN"9"152;
%"TAP"
"6","(-5600,2050)","0","mstr_standard","I32";
;
CDS_LIB"mstr_standard"
BODY_TYPE"PLUMBING"
HDL_TAP"TRUE";
"B \NAC \NWC"1;
"S \NAC"
BN"10"143;
%"TAP"
"6","(-5600,2100)","0","mstr_standard","I33";
;
CDS_LIB"mstr_standard"
BODY_TYPE"PLUMBING"
HDL_TAP"TRUE";
"B \NAC \NWC"1;
"S \NAC"
BN"11"142;
%"TAP"
"6","(-5600,2150)","0","mstr_standard","I34";
;
CDS_LIB"mstr_standard"
BODY_TYPE"PLUMBING"
HDL_TAP"TRUE";
"B \NAC \NWC"1;
"S \NAC"
BN"12"141;
%"TAP"
"6","(-5600,2200)","0","mstr_standard","I35";
;
CDS_LIB"mstr_standard"
BODY_TYPE"PLUMBING"
HDL_TAP"TRUE";
"B \NAC \NWC"1;
"S \NAC"
BN"13"140;
%"TAP"
"6","(-5600,2250)","0","mstr_standard","I36";
;
CDS_LIB"mstr_standard"
BODY_TYPE"PLUMBING"
HDL_TAP"TRUE";
"B \NAC \NWC"1;
"S \NAC"
BN"14"139;
%"TAP"
"6","(-5600,2300)","0","mstr_standard","I37";
;
CDS_LIB"mstr_standard"
BODY_TYPE"PLUMBING"
HDL_TAP"TRUE";
"B \NAC \NWC"1;
"S \NAC"
BN"15"138;
%"TAP"
"6","(-5600,2350)","0","mstr_standard","I38";
;
CDS_LIB"mstr_standard"
BODY_TYPE"PLUMBING"
HDL_TAP"TRUE";
"B \NAC \NWC"1;
"S \NAC"
BN"16"137;
%"TAP"
"6","(-5600,2400)","0","mstr_standard","I39";
;
CDS_LIB"mstr_standard"
BODY_TYPE"PLUMBING"
HDL_TAP"TRUE";
"B \NAC \NWC"1;
"S \NAC"
BN"17"136;
%"TAP"
"6","(-5600,2450)","0","mstr_standard","I40";
;
CDS_LIB"mstr_standard"
BODY_TYPE"PLUMBING"
HDL_TAP"TRUE";
"B \NAC \NWC"1;
"S \NAC"
BN"18"135;
%"TAP"
"6","(-5600,2500)","0","mstr_standard","I41";
;
CDS_LIB"mstr_standard"
BODY_TYPE"PLUMBING"
HDL_TAP"TRUE";
"B \NAC \NWC"1;
"S \NAC"
BN"19"134;
%"TAP"
"6","(-5600,2550)","0","mstr_standard","I42";
;
CDS_LIB"mstr_standard"
BODY_TYPE"PLUMBING"
HDL_TAP"TRUE";
"B \NAC \NWC"1;
"S \NAC"
BN"20"133;
%"TAP"
"6","(-5600,2600)","0","mstr_standard","I43";
;
CDS_LIB"mstr_standard"
BODY_TYPE"PLUMBING"
HDL_TAP"TRUE";
"B \NAC \NWC"1;
"S \NAC"
BN"21"132;
%"TAP"
"6","(-5600,2650)","0","mstr_standard","I44";
;
CDS_LIB"mstr_standard"
BODY_TYPE"PLUMBING"
HDL_TAP"TRUE";
"B \NAC \NWC"1;
"S \NAC"
BN"22"131;
%"TAP"
"6","(-5600,2700)","0","mstr_standard","I45";
;
CDS_LIB"mstr_standard"
BODY_TYPE"PLUMBING"
HDL_TAP"TRUE";
"B \NAC \NWC"1;
"S \NAC"
BN"23"130;
%"TAP"
"6","(-5600,2750)","0","mstr_standard","I46";
;
CDS_LIB"mstr_standard"
BODY_TYPE"PLUMBING"
HDL_TAP"TRUE";
"B \NAC \NWC"1;
"S \NAC"
BN"24"129;
%"TAP"
"6","(-5600,2850)","0","mstr_standard","I47";
;
CDS_LIB"mstr_standard"
BODY_TYPE"PLUMBING"
HDL_TAP"TRUE";
"B \NAC \NWC"1;
"S \NAC"
BN"26"127;
%"TAP"
"6","(-5600,2800)","0","mstr_standard","I48";
;
CDS_LIB"mstr_standard"
BODY_TYPE"PLUMBING"
HDL_TAP"TRUE";
"B \NAC \NWC"1;
"S \NAC"
BN"25"128;
%"TAP"
"6","(-5600,2900)","0","mstr_standard","I49";
;
CDS_LIB"mstr_standard"
BODY_TYPE"PLUMBING"
HDL_TAP"TRUE";
"B \NAC \NWC"1;
"S \NAC"
BN"27"126;
%"TAP"
"6","(-5600,650)","0","mstr_standard","I5";
;
CDS_LIB"mstr_standard"
BODY_TYPE"PLUMBING"
HDL_TAP"TRUE";
"B \NAC \NWC"4;
"S \NAC"
BN"0"147;
%"TAP"
"6","(-5600,2950)","0","mstr_standard","I50";
;
CDS_LIB"mstr_standard"
BODY_TYPE"PLUMBING"
HDL_TAP"TRUE";
"B \NAC \NWC"1;
"S \NAC"
BN"28"125;
%"TAP"
"6","(-5600,3000)","0","mstr_standard","I51";
;
CDS_LIB"mstr_standard"
BODY_TYPE"PLUMBING"
HDL_TAP"TRUE";
"B \NAC \NWC"1;
"S \NAC"
BN"29"124;
%"TAP"
"6","(-5600,3100)","0","mstr_standard","I52";
;
CDS_LIB"mstr_standard"
BODY_TYPE"PLUMBING"
HDL_TAP"TRUE";
"B \NAC \NWC"1;
"S \NAC"
BN"31"122;
%"TAP"
"6","(-5600,3050)","0","mstr_standard","I53";
;
CDS_LIB"mstr_standard"
BODY_TYPE"PLUMBING"
HDL_TAP"TRUE";
"B \NAC \NWC"1;
"S \NAC"
BN"30"123;
%"TAP"
"6","(-5600,3150)","0","mstr_standard","I54";
;
CDS_LIB"mstr_standard"
BODY_TYPE"PLUMBING"
HDL_TAP"TRUE";
"B \NAC \NWC"1;
"S \NAC"
BN"32"19;
%"TAP"
"6","(-5600,3200)","0","mstr_standard","I55";
;
CDS_LIB"mstr_standard"
BODY_TYPE"PLUMBING"
HDL_TAP"TRUE";
"B \NAC \NWC"1;
"S \NAC"
BN"33"121;
%"TAP"
"6","(-5600,3250)","0","mstr_standard","I56";
;
CDS_LIB"mstr_standard"
BODY_TYPE"PLUMBING"
HDL_TAP"TRUE";
"B \NAC \NWC"1;
"S \NAC"
BN"34"18;
%"TAP"
"6","(-5600,3350)","0","mstr_standard","I57";
;
CDS_LIB"mstr_standard"
BODY_TYPE"PLUMBING"
HDL_TAP"TRUE";
"B \NAC \NWC"1;
"S \NAC"
BN"36"119;
%"TAP"
"6","(-5600,3300)","0","mstr_standard","I58";
;
CDS_LIB"mstr_standard"
BODY_TYPE"PLUMBING"
HDL_TAP"TRUE";
"B \NAC \NWC"1;
"S \NAC"
BN"35"120;
%"TAP"
"6","(-5600,3400)","0","mstr_standard","I59";
;
CDS_LIB"mstr_standard"
BODY_TYPE"PLUMBING"
HDL_TAP"TRUE";
"B \NAC \NWC"1;
"S \NAC"
BN"37"20;
%"TAP"
"6","(-5600,700)","0","mstr_standard","I6";
;
CDS_LIB"mstr_standard"
BODY_TYPE"PLUMBING"
HDL_TAP"TRUE";
"B \NAC \NWC"4;
"S \NAC"
BN"1"146;
%"TAP"
"6","(-5600,3450)","0","mstr_standard","I60";
;
CDS_LIB"mstr_standard"
BODY_TYPE"PLUMBING"
HDL_TAP"TRUE";
"B \NAC \NWC"1;
"S \NAC"
BN"38"118;
%"TAP"
"6","(-5600,3500)","0","mstr_standard","I61";
;
CDS_LIB"mstr_standard"
BODY_TYPE"PLUMBING"
HDL_TAP"TRUE";
"B \NAC \NWC"1;
"S \NAC"
BN"39"117;
%"TAP"
"6","(-5600,3550)","0","mstr_standard","I62";
;
CDS_LIB"mstr_standard"
BODY_TYPE"PLUMBING"
HDL_TAP"TRUE";
"B \NAC \NWC"1;
"S \NAC"
BN"40"14;
%"TAP"
"6","(-5600,3600)","0","mstr_standard","I63";
;
CDS_LIB"mstr_standard"
BODY_TYPE"PLUMBING"
HDL_TAP"TRUE";
"B \NAC \NWC"1;
"S \NAC"
BN"41"116;
%"TAP"
"6","(-5600,3650)","0","mstr_standard","I64";
;
CDS_LIB"mstr_standard"
BODY_TYPE"PLUMBING"
HDL_TAP"TRUE";
"B \NAC \NWC"1;
"S \NAC"
BN"42"115;
%"TAP"
"6","(-5600,3700)","0","mstr_standard","I65";
;
CDS_LIB"mstr_standard"
BODY_TYPE"PLUMBING"
HDL_TAP"TRUE";
"B \NAC \NWC"1;
"S \NAC"
BN"43"114;
%"TAP"
"6","(-5600,3750)","0","mstr_standard","I66";
;
CDS_LIB"mstr_standard"
BODY_TYPE"PLUMBING"
HDL_TAP"TRUE";
"B \NAC \NWC"1;
"S \NAC"
BN"44"113;
%"TAP"
"6","(-5600,3800)","0","mstr_standard","I67";
;
CDS_LIB"mstr_standard"
BODY_TYPE"PLUMBING"
HDL_TAP"TRUE";
"B \NAC \NWC"1;
"S \NAC"
BN"45"112;
%"TAP"
"6","(-5600,3850)","0","mstr_standard","I68";
;
CDS_LIB"mstr_standard"
BODY_TYPE"PLUMBING"
HDL_TAP"TRUE";
"B \NAC \NWC"1;
"S \NAC"
BN"46"111;
%"TAP"
"6","(-5600,3900)","0","mstr_standard","I69";
;
CDS_LIB"mstr_standard"
BODY_TYPE"PLUMBING"
HDL_TAP"TRUE";
"B \NAC \NWC"1;
"S \NAC"
BN"47"110;
%"TAP"
"6","(-5600,800)","0","mstr_standard","I7";
;
CDS_LIB"mstr_standard"
BODY_TYPE"PLUMBING"
HDL_TAP"TRUE";
"B \NAC \NWC"4;
"S \NAC"
BN"3"144;
%"TAP"
"6","(-5600,3950)","0","mstr_standard","I70";
;
CDS_LIB"mstr_standard"
BODY_TYPE"PLUMBING"
HDL_TAP"TRUE";
"B \NAC \NWC"1;
"S \NAC"
BN"48"109;
%"TAP"
"6","(-5600,4000)","0","mstr_standard","I71";
;
CDS_LIB"mstr_standard"
BODY_TYPE"PLUMBING"
HDL_TAP"TRUE";
"B \NAC \NWC"1;
"S \NAC"
BN"49"108;
%"TAP"
"6","(-5600,4050)","0","mstr_standard","I73";
;
CDS_LIB"mstr_standard"
BODY_TYPE"PLUMBING"
HDL_TAP"TRUE";
"B \NAC \NWC"1;
"S \NAC"
BN"50"107;
%"TAP"
"6","(-5600,4100)","0","mstr_standard","I74";
;
CDS_LIB"mstr_standard"
BODY_TYPE"PLUMBING"
HDL_TAP"TRUE";
"B \NAC \NWC"1;
"S \NAC"
BN"51"106;
%"TAP"
"6","(-5600,4150)","0","mstr_standard","I75";
;
CDS_LIB"mstr_standard"
BODY_TYPE"PLUMBING"
HDL_TAP"TRUE";
"B \NAC \NWC"1;
"S \NAC"
BN"52"16;
%"TAP"
"6","(-5600,4200)","0","mstr_standard","I76";
;
CDS_LIB"mstr_standard"
BODY_TYPE"PLUMBING"
HDL_TAP"TRUE";
"B \NAC \NWC"1;
"S \NAC"
BN"53"105;
%"TAP"
"6","(-5600,4250)","0","mstr_standard","I77";
;
CDS_LIB"mstr_standard"
BODY_TYPE"PLUMBING"
HDL_TAP"TRUE";
"B \NAC \NWC"1;
"S \NAC"
BN"54"13;
%"TAP"
"6","(-5600,4300)","0","mstr_standard","I78";
;
CDS_LIB"mstr_standard"
BODY_TYPE"PLUMBING"
HDL_TAP"TRUE";
"B \NAC \NWC"1;
"S \NAC"
BN"55"104;
%"TAP"
"6","(-5600,4350)","0","mstr_standard","I79";
;
CDS_LIB"mstr_standard"
BODY_TYPE"PLUMBING"
HDL_TAP"TRUE";
"B \NAC \NWC"1;
"S \NAC"
BN"56"103;
%"TAP"
"6","(-5600,750)","0","mstr_standard","I8";
;
CDS_LIB"mstr_standard"
BODY_TYPE"PLUMBING"
HDL_TAP"TRUE";
"B \NAC \NWC"4;
"S \NAC"
BN"2"145;
%"TAP"
"6","(-5600,4400)","0","mstr_standard","I80";
;
CDS_LIB"mstr_standard"
BODY_TYPE"PLUMBING"
HDL_TAP"TRUE";
"B \NAC \NWC"1;
"S \NAC"
BN"57"102;
%"TAP"
"6","(-5600,4450)","0","mstr_standard","I81";
;
CDS_LIB"mstr_standard"
BODY_TYPE"PLUMBING"
HDL_TAP"TRUE";
"B \NAC \NWC"1;
"S \NAC"
BN"58"101;
%"TAP"
"6","(-5600,4500)","0","mstr_standard","I82";
;
CDS_LIB"mstr_standard"
BODY_TYPE"PLUMBING"
HDL_TAP"TRUE";
"B \NAC \NWC"1;
"S \NAC"
BN"59"100;
%"TAP"
"6","(-5600,4550)","0","mstr_standard","I83";
;
CDS_LIB"mstr_standard"
BODY_TYPE"PLUMBING"
HDL_TAP"TRUE";
"B \NAC \NWC"1;
"S \NAC"
BN"60"99;
%"TAP"
"6","(-5600,4600)","0","mstr_standard","I84";
;
CDS_LIB"mstr_standard"
BODY_TYPE"PLUMBING"
HDL_TAP"TRUE";
"B \NAC \NWC"1;
"S \NAC"
BN"61"98;
%"TAP"
"6","(-5600,4650)","0","mstr_standard","I85";
;
CDS_LIB"mstr_standard"
BODY_TYPE"PLUMBING"
HDL_TAP"TRUE";
"B \NAC \NWC"1;
"S \NAC"
BN"62"97;
%"TAP"
"6","(-5600,4700)","0","mstr_standard","I86";
;
CDS_LIB"mstr_standard"
BODY_TYPE"PLUMBING"
HDL_TAP"TRUE";
"B \NAC \NWC"1;
"S \NAC"
BN"63"96;
%"TAP"
"6","(-2875,800)","2","mstr_standard","I87";
;
CDS_LIB"mstr_standard"
BODY_TYPE"PLUMBING"
HDL_TAP"TRUE";
"B \NAC \NWC"10;
"S \NAC"
BN"1"75;
%"TAP"
"6","(-2875,750)","2","mstr_standard","I88";
;
CDS_LIB"mstr_standard"
BODY_TYPE"PLUMBING"
HDL_TAP"TRUE";
"B \NAC \NWC"10;
"S \NAC"
BN"0"76;
%"TAP"
"6","(-2875,900)","2","mstr_standard","I89";
;
CDS_LIB"mstr_standard"
BODY_TYPE"PLUMBING"
HDL_TAP"TRUE";
"B \NAC \NWC"9;
"S \NAC"
BN"1"77;
%"TAP"
"6","(-5600,900)","0","mstr_standard","I9";
;
CDS_LIB"mstr_standard"
BODY_TYPE"PLUMBING"
HDL_TAP"TRUE";
"B \NAC \NWC"3;
"S \NAC"
BN"1"150;
%"TAP"
"6","(-2875,850)","2","mstr_standard","I90";
;
CDS_LIB"mstr_standard"
BODY_TYPE"PLUMBING"
HDL_TAP"TRUE";
"B \NAC \NWC"9;
"S \NAC"
BN"0"78;
%"TAP"
"6","(-2875,1150)","2","mstr_standard","I91";
;
CDS_LIB"mstr_standard"
BODY_TYPE"PLUMBING"
HDL_TAP"TRUE";
"B \NAC \NWC"7;
"S \NAC"
BN"3"87;
%"TAP"
"6","(-2875,1200)","2","mstr_standard","I92";
;
CDS_LIB"mstr_standard"
BODY_TYPE"PLUMBING"
HDL_TAP"TRUE";
"B \NAC \NWC"7;
"S \NAC"
BN"4"86;
%"TAP"
"6","(-2875,1100)","2","mstr_standard","I93";
;
CDS_LIB"mstr_standard"
BODY_TYPE"PLUMBING"
HDL_TAP"TRUE";
"B \NAC \NWC"7;
"S \NAC"
BN"2"88;
%"TAP"
"6","(-2875,1050)","2","mstr_standard","I94";
;
CDS_LIB"mstr_standard"
BODY_TYPE"PLUMBING"
HDL_TAP"TRUE";
"B \NAC \NWC"7;
"S \NAC"
BN"1"89;
%"TAP"
"6","(-2875,1000)","2","mstr_standard","I95";
;
CDS_LIB"mstr_standard"
BODY_TYPE"PLUMBING"
HDL_TAP"TRUE";
"B \NAC \NWC"7;
"S \NAC"
BN"0"90;
%"TAP"
"6","(-2875,1300)","2","mstr_standard","I96";
;
CDS_LIB"mstr_standard"
BODY_TYPE"PLUMBING"
HDL_TAP"TRUE";
"B \NAC \NWC"7;
"S \NAC"
BN"6"84;
%"TAP"
"6","(-2875,1350)","2","mstr_standard","I97";
;
CDS_LIB"mstr_standard"
BODY_TYPE"PLUMBING"
HDL_TAP"TRUE";
"B \NAC \NWC"7;
"S \NAC"
BN"7"83;
%"TAP"
"6","(-2875,1250)","2","mstr_standard","I98";
;
CDS_LIB"mstr_standard"
BODY_TYPE"PLUMBING"
HDL_TAP"TRUE";
"B \NAC \NWC"7;
"S \NAC"
BN"5"85;
%"TAP"
"6","(-2875,1450)","2","mstr_standard","I99";
;
CDS_LIB"mstr_standard"
BODY_TYPE"PLUMBING"
HDL_TAP"TRUE";
"B \NAC \NWC"5;
"S \NAC"
BN"0"95;
END.
